(kicad_pcb
	(version 20260206)
	(generator "pcbnew")
	(generator_version "10.0")
	(general
		(thickness 1.6)
		(legacy_teardrops no)
	)
	(paper "A4")
	(title_block
		(title "Wiwynn_Tioga_Pass_MB.brd")
		(comment 1 "Tioga Pass / footprints 3818-3825 of 4770")
	)
	(layers
		(0 "F.Cu" signal "TOP")
		(4 "In1.Cu" signal "L2GND")
		(6 "In2.Cu" signal "L3")
		(8 "In3.Cu" signal "L4GND")
		(10 "In4.Cu" signal "L5")
		(12 "In5.Cu" signal "L6GND")
		(14 "In6.Cu" signal "L7VCC")
		(16 "In7.Cu" signal "L8VCC")
		(18 "In8.Cu" signal "L9GND")
		(20 "In9.Cu" signal "L10")
		(22 "In10.Cu" signal "L11GND")
		(24 "In11.Cu" signal "L12")
		(26 "In12.Cu" signal "L13GND")
		(2 "B.Cu" signal "BOTTOM")
		(9 "F.Adhes" user "F.Adhesive")
		(11 "B.Adhes" user "B.Adhesive")
		(13 "F.Paste" user "Package Geometry/Pastemask Top")
		(15 "B.Paste" user "Package Geometry/Pastemask Bottom")
		(5 "F.SilkS" user "Ref Des/Silkscreen Top")
		(7 "B.SilkS" user "Ref Des/Silkscreen Bottom")
		(1 "F.Mask" user "Board Geometry/Soldermask Top")
		(3 "B.Mask" user "Board Geometry/Soldermask Bottom")
		(17 "Dwgs.User" user "User.Drawings")
		(19 "Cmts.User" user "User.Comments")
		(21 "Eco1.User" user "User.Eco1")
		(23 "Eco2.User" user "User.Eco2")
		(25 "Edge.Cuts" user "Board Geometry/Outline")
		(27 "Margin" user)
		(31 "F.CrtYd" user "Package Geometry/Place Bound Top")
		(29 "B.CrtYd" user "Package Geometry/Place Bound Bottom")
		(35 "F.Fab" user "Ref Des/Assembly Top")
		(33 "B.Fab" user "Ref Des/Assembly Bottom")
	)
	(footprint ""
		(layer "B.Cu")
		(at 493.644428 -41.405048 180)
		(property "Reference" "R25W138"
			(at 0.8382 -0.67818 180)
			(unlocked yes)
			(layer "B.SilkS")
			(effects
				(font
					(size 0.4064 0.254)
					(thickness 0.1524)
				)
				(justify left mirror)
			)
		)
		(property "Value" ""
			(at 0 0 0)
			(layer "B.Fab")
			(effects
				(font
					(size 1.27 1.27)
				)
				(justify mirror)
			)
		)
		(duplicate_pad_numbers_are_jumpers no)
		(fp_poly
			(pts
				(xy 0.2794 -0.1016) (xy -0.2794 -0.1016) (xy -0.2794 0.9906) (xy 0.2794 0.9906)
			)
			(stroke
				(width 0)
				(type default)
			)
			(fill no)
			(layer "B.CrtYd")
		)
		(fp_line
			(start 0.2794 0.9906)
			(end -0.2794 0.9906)
			(stroke
				(width 0.1)
				(type default)
			)
			(layer "B.Fab")
		)
		(fp_line
			(start 0.2794 -0.1016)
			(end 0.2794 0.9906)
			(stroke
				(width 0.1)
				(type default)
			)
			(layer "B.Fab")
		)
		(fp_line
			(start -0.2794 0.9906)
			(end -0.2794 -0.1016)
			(stroke
				(width 0.1)
				(type default)
			)
			(layer "B.Fab")
		)
		(fp_line
			(start -0.2794 -0.1016)
			(end 0.2794 -0.1016)
			(stroke
				(width 0.1)
				(type default)
			)
			(layer "B.Fab")
		)
		(pad "1" smd rect
			(at 0 0)
			(size 0.508 0.508)
			(layers "B.Cu" "B.Mask" "B.Paste")
			(net "VGA_REAR_HSYNC_S")
		)
		(pad "2" smd rect
			(at 0 0.889)
			(size 0.508 0.508)
			(layers "B.Cu" "B.Mask" "B.Paste")
			(net "V_IO_HSYNC_J")
		)
		(zone
			(layer "B.Cu")
			(hatch none 0.5)
			(connect_pads
				(clearance 0)
			)
			(min_thickness 0.25)
			(keepout
				(tracks not_allowed)
				(vias allowed)
				(pads allowed)
				(copperpour not_allowed)
				(footprints allowed)
			)
			(placement
				(enabled no)
				(sheetname "")
			)
			(fill
				(thermal_gap 0.5)
				(thermal_bridge_width 0.5)
				(island_removal_mode 0)
			)
			(polygon
				(pts
					(xy 493.390428 -42.040048) (xy 493.898428 -42.040048) (xy 493.898428 -41.659048) (xy 493.390428 -41.659048)
				)
			)
		)
		(zone
			(layer "B.Cu")
			(hatch none 0.5)
			(connect_pads
				(clearance 0)
			)
			(min_thickness 0.25)
			(keepout
				(tracks allowed)
				(vias not_allowed)
				(pads allowed)
				(copperpour not_allowed)
				(footprints allowed)
			)
			(placement
				(enabled no)
				(sheetname "")
			)
			(fill
				(thermal_gap 0.5)
				(thermal_bridge_width 0.5)
				(island_removal_mode 0)
			)
			(polygon
				(pts
					(xy 493.390428 -41.659048) (xy 493.898428 -41.659048) (xy 493.898428 -42.040048) (xy 493.390428 -42.040048)
				)
			)
		)
	)
	(footprint ""
		(layer "B.Cu")
		(at 348.129606 -0.679704 -90)
		(property "Reference" "R3U9"
			(at 0 0 90)
			(layer "B.SilkS")
			(hide yes)
			(effects
				(font
					(size 1.27 1.27)
				)
				(justify mirror)
			)
		)
		(property "Value" ""
			(at 0 0 90)
			(layer "B.Fab")
			(effects
				(font
					(size 1.27 1.27)
				)
				(justify mirror)
			)
		)
		(duplicate_pad_numbers_are_jumpers no)
		(fp_rect
			(start -0.2794 0.9906)
			(end 0.2794 -0.1016)
			(stroke
				(width 0)
				(type default)
			)
			(fill no)
			(layer "B.CrtYd")
		)
		(fp_line
			(start -0.2794 0.9906)
			(end -0.2794 -0.1016)
			(stroke
				(width 0.1)
				(type default)
			)
			(layer "B.Fab")
		)
		(fp_line
			(start 0.2794 0.9906)
			(end -0.2794 0.9906)
			(stroke
				(width 0.1)
				(type default)
			)
			(layer "B.Fab")
		)
		(fp_line
			(start -0.2794 -0.1016)
			(end 0.2794 -0.1016)
			(stroke
				(width 0.1)
				(type default)
			)
			(layer "B.Fab")
		)
		(fp_line
			(start 0.2794 -0.1016)
			(end 0.2794 0.9906)
			(stroke
				(width 0.1)
				(type default)
			)
			(layer "B.Fab")
		)
		(pad "1" smd rect
			(at 0 0 90)
			(size 0.508 0.508)
			(layers "B.Cu" "B.Mask" "B.Paste")
			(net "VR_PVDDQ_ABC_PH2_VCIN")
		)
		(pad "2" smd rect
			(at 0 0.889 90)
			(size 0.508 0.508)
			(layers "B.Cu" "B.Mask" "B.Paste")
			(net "P5V_STBY")
		)
		(zone
			(layer "B.Cu")
			(hatch none 0.5)
			(connect_pads
				(clearance 0)
			)
			(min_thickness 0.25)
			(keepout
				(tracks not_allowed)
				(vias allowed)
				(pads allowed)
				(copperpour not_allowed)
				(footprints allowed)
			)
			(placement
				(enabled no)
				(sheetname "")
			)
			(fill
				(thermal_gap 0.5)
				(thermal_bridge_width 0.5)
				(island_removal_mode 0)
			)
			(polygon
				(pts
					(xy 347.494606 -0.933704) (xy 347.494606 -0.425704) (xy 347.875606 -0.425704) (xy 347.875606 -0.933704)
				)
			)
		)
		(zone
			(layer "B.Cu")
			(hatch none 0.5)
			(connect_pads
				(clearance 0)
			)
			(min_thickness 0.25)
			(keepout
				(tracks allowed)
				(vias not_allowed)
				(pads allowed)
				(copperpour not_allowed)
				(footprints allowed)
			)
			(placement
				(enabled no)
				(sheetname "")
			)
			(fill
				(thermal_gap 0.5)
				(thermal_bridge_width 0.5)
				(island_removal_mode 0)
			)
			(polygon
				(pts
					(xy 347.494606 -0.933704) (xy 347.494606 -0.425704) (xy 347.875606 -0.425704) (xy 347.875606 -0.933704)
				)
			)
		)
	)
	(footprint ""
		(layer "B.Cu")
		(at 405.8285 -22.987 -90)
		(property "Reference" "C25W62"
			(at -0.97536 0.76708 0)
			(unlocked yes)
			(layer "B.SilkS")
			(effects
				(font
					(size 0.4064 0.254)
					(thickness 0.1524)
				)
				(justify mirror)
			)
		)
		(property "Value" ""
			(at 0 0 90)
			(layer "B.Fab")
			(effects
				(font
					(size 1.27 1.27)
				)
				(justify mirror)
			)
		)
		(duplicate_pad_numbers_are_jumpers no)
		(fp_poly
			(pts
				(xy 0.4953 -0.2032) (xy -0.4953 -0.2032) (xy -0.4953 1.6002) (xy 0.4953 1.6002)
			)
			(stroke
				(width 0)
				(type default)
			)
			(fill no)
			(layer "B.CrtYd")
		)
		(fp_line
			(start -0.4953 1.6002)
			(end 0.4953 1.6002)
			(stroke
				(width 0.1)
				(type default)
			)
			(layer "B.Fab")
		)
		(fp_line
			(start 0.4953 1.6002)
			(end 0.4953 -0.2032)
			(stroke
				(width 0.1)
				(type default)
			)
			(layer "B.Fab")
		)
		(fp_line
			(start -0.4953 -0.2032)
			(end -0.4953 1.6002)
			(stroke
				(width 0.1)
				(type default)
			)
			(layer "B.Fab")
		)
		(fp_line
			(start 0.4953 -0.2032)
			(end -0.4953 -0.2032)
			(stroke
				(width 0.1)
				(type default)
			)
			(layer "B.Fab")
		)
		(pad "1" smd rect
			(at 0 0 90)
			(size 0.762 0.889)
			(layers "B.Cu" "B.Mask" "B.Paste")
			(net "P3V3_STBY")
		)
		(pad "2" smd rect
			(at 0 1.397 90)
			(size 0.762 0.889)
			(layers "B.Cu" "B.Mask" "B.Paste")
			(net "GND")
		)
		(zone
			(layer "B.Cu")
			(hatch none 0.5)
			(connect_pads
				(clearance 0)
			)
			(min_thickness 0.25)
			(keepout
				(tracks not_allowed)
				(vias allowed)
				(pads allowed)
				(copperpour not_allowed)
				(footprints allowed)
			)
			(placement
				(enabled no)
				(sheetname "")
			)
			(fill
				(thermal_gap 0.5)
				(thermal_bridge_width 0.5)
				(island_removal_mode 0)
			)
			(polygon
				(pts
					(xy 405.384 -22.606) (xy 405.384 -23.368) (xy 404.876 -23.368) (xy 404.876 -22.606)
				)
			)
		)
	)
	(footprint ""
		(layer "B.Cu")
		(at 39.307516 -106.085386 -90)
		(property "Reference" "R1C3"
			(at 0 0 90)
			(layer "B.SilkS")
			(hide yes)
			(effects
				(font
					(size 1.27 1.27)
				)
				(justify mirror)
			)
		)
		(property "Value" ""
			(at 0 0 90)
			(layer "B.Fab")
			(effects
				(font
					(size 1.27 1.27)
				)
				(justify mirror)
			)
		)
		(duplicate_pad_numbers_are_jumpers no)
		(fp_poly
			(pts
				(xy 0.2794 -0.1016) (xy -0.2794 -0.1016) (xy -0.2794 0.9906) (xy 0.2794 0.9906)
			)
			(stroke
				(width 0)
				(type default)
			)
			(fill no)
			(layer "B.CrtYd")
		)
		(fp_line
			(start -0.2794 0.9906)
			(end -0.2794 -0.1016)
			(stroke
				(width 0.1)
				(type default)
			)
			(layer "B.Fab")
		)
		(fp_line
			(start 0.2794 0.9906)
			(end -0.2794 0.9906)
			(stroke
				(width 0.1)
				(type default)
			)
			(layer "B.Fab")
		)
		(fp_line
			(start -0.2794 -0.1016)
			(end 0.2794 -0.1016)
			(stroke
				(width 0.1)
				(type default)
			)
			(layer "B.Fab")
		)
		(fp_line
			(start 0.2794 -0.1016)
			(end 0.2794 0.9906)
			(stroke
				(width 0.1)
				(type default)
			)
			(layer "B.Fab")
		)
		(pad "1" smd rect
			(at 0 0 90)
			(size 0.508 0.508)
			(layers "B.Cu" "B.Mask" "B.Paste")
			(net "SVID_CLK1_CPU1")
		)
		(pad "2" smd rect
			(at 0 0.889 90)
			(size 0.508 0.508)
			(layers "B.Cu" "B.Mask" "B.Paste")
			(net "SVID_CLK1_CPU1_R")
		)
		(zone
			(layer "B.Cu")
			(hatch none 0.5)
			(connect_pads
				(clearance 0)
			)
			(min_thickness 0.25)
			(keepout
				(tracks not_allowed)
				(vias allowed)
				(pads allowed)
				(copperpour not_allowed)
				(footprints allowed)
			)
			(placement
				(enabled no)
				(sheetname "")
			)
			(fill
				(thermal_gap 0.5)
				(thermal_bridge_width 0.5)
				(island_removal_mode 0)
			)
			(polygon
				(pts
					(xy 38.672516 -105.831386) (xy 38.672516 -106.339386) (xy 39.053516 -106.339386) (xy 39.053516 -105.831386)
				)
			)
		)
		(zone
			(layer "B.Cu")
			(hatch none 0.5)
			(connect_pads
				(clearance 0)
			)
			(min_thickness 0.25)
			(keepout
				(tracks allowed)
				(vias not_allowed)
				(pads allowed)
				(copperpour not_allowed)
				(footprints allowed)
			)
			(placement
				(enabled no)
				(sheetname "")
			)
			(fill
				(thermal_gap 0.5)
				(thermal_bridge_width 0.5)
				(island_removal_mode 0)
			)
			(polygon
				(pts
					(xy 39.053516 -105.831386) (xy 39.053516 -106.339386) (xy 38.672516 -106.339386) (xy 38.672516 -105.831386)
				)
			)
		)
	)
	(footprint ""
		(layer "B.Cu")
		(at 360.555794 -43.956986 90)
		(property "Reference" "R2T62"
			(at 0 0 90)
			(layer "B.SilkS")
			(hide yes)
			(effects
				(font
					(size 1.27 1.27)
				)
				(justify mirror)
			)
		)
		(property "Value" ""
			(at 0 0 90)
			(layer "B.Fab")
			(effects
				(font
					(size 1.27 1.27)
				)
				(justify mirror)
			)
		)
		(duplicate_pad_numbers_are_jumpers no)
		(fp_poly
			(pts
				(xy 0.2794 -0.1016) (xy -0.2794 -0.1016) (xy -0.2794 0.9906) (xy 0.2794 0.9906)
			)
			(stroke
				(width 0)
				(type default)
			)
			(fill no)
			(layer "B.CrtYd")
		)
		(fp_line
			(start 0.2794 -0.1016)
			(end 0.2794 0.9906)
			(stroke
				(width 0.1)
				(type default)
			)
			(layer "B.Fab")
		)
		(fp_line
			(start -0.2794 -0.1016)
			(end 0.2794 -0.1016)
			(stroke
				(width 0.1)
				(type default)
			)
			(layer "B.Fab")
		)
		(fp_line
			(start 0.2794 0.9906)
			(end -0.2794 0.9906)
			(stroke
				(width 0.1)
				(type default)
			)
			(layer "B.Fab")
		)
		(fp_line
			(start -0.2794 0.9906)
			(end -0.2794 -0.1016)
			(stroke
				(width 0.1)
				(type default)
			)
			(layer "B.Fab")
		)
		(pad "1" smd rect
			(at 0 0 270)
			(size 0.508 0.508)
			(layers "B.Cu" "B.Mask" "B.Paste")
			(net "H_CPU_ERR1_PCH_N")
		)
		(pad "2" smd rect
			(at 0 0.889 270)
			(size 0.508 0.508)
			(layers "B.Cu" "B.Mask" "B.Paste")
			(net "FM_CPU_ERR1_LVT3_K_N")
		)
		(zone
			(layer "B.Cu")
			(hatch none 0.5)
			(connect_pads
				(clearance 0)
			)
			(min_thickness 0.25)
			(keepout
				(tracks allowed)
				(vias not_allowed)
				(pads allowed)
				(copperpour not_allowed)
				(footprints allowed)
			)
			(placement
				(enabled no)
				(sheetname "")
			)
			(fill
				(thermal_gap 0.5)
				(thermal_bridge_width 0.5)
				(island_removal_mode 0)
			)
			(polygon
				(pts
					(xy 360.809794 -44.210986) (xy 360.809794 -43.702986) (xy 361.190794 -43.702986) (xy 361.190794 -44.210986)
				)
			)
		)
		(zone
			(layer "B.Cu")
			(hatch none 0.5)
			(connect_pads
				(clearance 0)
			)
			(min_thickness 0.25)
			(keepout
				(tracks not_allowed)
				(vias allowed)
				(pads allowed)
				(copperpour not_allowed)
				(footprints allowed)
			)
			(placement
				(enabled no)
				(sheetname "")
			)
			(fill
				(thermal_gap 0.5)
				(thermal_bridge_width 0.5)
				(island_removal_mode 0)
			)
			(polygon
				(pts
					(xy 361.190794 -44.210986) (xy 361.190794 -43.702986) (xy 360.809794 -43.702986) (xy 360.809794 -44.210986)
				)
			)
		)
	)
	(footprint ""
		(layer "B.Cu")
		(at 343.066878 -91.46413 -90)
		(property "Reference" "CF13"
			(at 0 0 90)
			(layer "B.SilkS")
			(hide yes)
			(effects
				(font
					(size 1.27 1.27)
				)
				(justify mirror)
			)
		)
		(property "Value" "*"
			(at -1.1811 -2.8194 270)
			(unlocked yes)
			(layer "B.Fab")
			(hide yes)
			(effects
				(font
					(size 1.27 1.016)
					(thickness 0.1524)
				)
				(justify mirror)
			)
		)
		(property "Device Type" "SC22P50V2JN-4GP_SMD-BCG-SC22P5A"
			(at -1.1811 -4.3434 270)
			(unlocked yes)
			(layer "B.Fab")
			(hide yes)
			(effects
				(font
					(size 1.27 1.016)
					(thickness 0.1524)
				)
				(justify mirror)
			)
		)
		(duplicate_pad_numbers_are_jumpers no)
		(fp_rect
			(start 0.4318 0.9525)
			(end -0.4318 -0.9525)
			(stroke
				(width 0)
				(type default)
			)
			(fill no)
			(layer "B.CrtYd")
		)
		(fp_rect
			(start 0.4318 0.9525)
			(end -0.4318 -0.9525)
			(stroke
				(width 0)
				(type default)
			)
			(fill no)
			(layer "B.Fab")
		)
		(pad "1" smd custom
			(at 0 -0.4445 90)
			(size 0.1524 0.1524)
			(layers "B.Cu" "B.Mask" "B.Paste")
			(net "VR_PVCCIO_CPU0_AIREF1")
			(options
				(clearance outline)
				(anchor circle)
			)
			(primitives
				(gr_poly
					(pts
						(arc
							(start 0.3048 0.2032)
							(mid 0.275042 0.275042)
							(end 0.2032 0.3048)
						)
						(arc
							(start -0.2032 0.3048)
							(mid -0.275042 0.275042)
							(end -0.3048 0.2032)
						)
						(arc
							(start -0.3048 -0.2032)
							(mid -0.275042 -0.275042)
							(end -0.2032 -0.3048)
						)
						(arc
							(start 0.2032 -0.3048)
							(mid 0.275042 -0.275042)
							(end 0.3048 -0.2032)
						)
					)
					(width 0)
					(fill yes)
				)
			)
		)
		(pad "2" smd custom
			(at 0 0.4445 90)
			(size 0.1524 0.1524)
			(layers "B.Cu" "B.Mask" "B.Paste")
			(net "ISENSE_PVCCIO_CPU0_PH1_IMON")
			(options
				(clearance outline)
				(anchor circle)
			)
			(primitives
				(gr_poly
					(pts
						(arc
							(start 0.3048 0.2032)
							(mid 0.275042 0.275042)
							(end 0.2032 0.3048)
						)
						(arc
							(start -0.2032 0.3048)
							(mid -0.275042 0.275042)
							(end -0.3048 0.2032)
						)
						(arc
							(start -0.3048 -0.2032)
							(mid -0.275042 -0.275042)
							(end -0.2032 -0.3048)
						)
						(arc
							(start 0.2032 -0.3048)
							(mid 0.275042 -0.275042)
							(end 0.3048 -0.2032)
						)
					)
					(width 0)
					(fill yes)
				)
			)
		)
	)
	(footprint ""
		(layer "B.Cu")
		(at 245.7323 -149.8092 -90)
		(property "Reference" "C5G59"
			(at -1.14681 0.76708 0)
			(unlocked yes)
			(layer "B.SilkS")
			(effects
				(font
					(size 0.7874 0.5842)
					(thickness 0.1524)
				)
				(justify mirror)
			)
		)
		(property "Value" ""
			(at 0 0 90)
			(layer "B.Fab")
			(effects
				(font
					(size 1.27 1.27)
				)
				(justify mirror)
			)
		)
		(duplicate_pad_numbers_are_jumpers no)
		(fp_rect
			(start 0.4953 1.6002)
			(end -0.4953 -0.2032)
			(stroke
				(width 0)
				(type default)
			)
			(fill no)
			(layer "B.CrtYd")
		)
		(fp_line
			(start -0.4953 1.6002)
			(end 0.4953 1.6002)
			(stroke
				(width 0.1)
				(type default)
			)
			(layer "B.Fab")
		)
		(fp_line
			(start 0.4953 1.6002)
			(end 0.4953 -0.2032)
			(stroke
				(width 0.1)
				(type default)
			)
			(layer "B.Fab")
		)
		(fp_line
			(start -0.4953 -0.2032)
			(end -0.4953 1.6002)
			(stroke
				(width 0.1)
				(type default)
			)
			(layer "B.Fab")
		)
		(fp_line
			(start 0.4953 -0.2032)
			(end -0.4953 -0.2032)
			(stroke
				(width 0.1)
				(type default)
			)
			(layer "B.Fab")
		)
		(pad "1" smd rect
			(at 0 0 90)
			(size 0.762 0.889)
			(layers "B.Cu" "B.Mask" "B.Paste")
			(net "PVDDQ_DEF")
		)
		(pad "2" smd rect
			(at 0 1.397 90)
			(size 0.762 0.889)
			(layers "B.Cu" "B.Mask" "B.Paste")
			(net "GND")
		)
		(zone
			(layer "B.Cu")
			(hatch none 0.5)
			(connect_pads
				(clearance 0)
			)
			(min_thickness 0.25)
			(keepout
				(tracks not_allowed)
				(vias allowed)
				(pads allowed)
				(copperpour not_allowed)
				(footprints allowed)
			)
			(placement
				(enabled no)
				(sheetname "")
			)
			(fill
				(thermal_gap 0.5)
				(thermal_bridge_width 0.5)
				(island_removal_mode 0)
			)
			(polygon
				(pts
					(xy 244.7798 -149.4282) (xy 245.2878 -149.4282) (xy 245.2878 -150.1902) (xy 244.7798 -150.1902)
				)
			)
		)
	)
	(footprint ""
		(layer "B.Cu")
		(at 185.25109 0.139192 180)
		(property "Reference" "C6U15"
			(at 0 0 0)
			(layer "B.SilkS")
			(hide yes)
			(effects
				(font
					(size 1.27 1.27)
				)
				(justify mirror)
			)
		)
		(property "Value" ""
			(at 0 0 0)
			(layer "B.Fab")
			(effects
				(font
					(size 1.27 1.27)
				)
				(justify mirror)
			)
		)
		(duplicate_pad_numbers_are_jumpers no)
		(fp_rect
			(start 0.4953 -0.2032)
			(end -0.4953 1.6002)
			(stroke
				(width 0)
				(type default)
			)
			(fill no)
			(layer "B.CrtYd")
		)
		(fp_line
			(start 0.4953 1.6002)
			(end 0.4953 -0.2032)
			(stroke
				(width 0.1)
				(type default)
			)
			(layer "B.Fab")
		)
		(fp_line
			(start 0.4953 -0.2032)
			(end -0.4953 -0.2032)
			(stroke
				(width 0.1)
				(type default)
			)
			(layer "B.Fab")
		)
		(fp_line
			(start -0.4953 1.6002)
			(end 0.4953 1.6002)
			(stroke
				(width 0.1)
				(type default)
			)
			(layer "B.Fab")
		)
		(fp_line
			(start -0.4953 -0.2032)
			(end -0.4953 1.6002)
			(stroke
				(width 0.1)
				(type default)
			)
			(layer "B.Fab")
		)
		(pad "1" smd rect
			(at 0 0)
			(size 0.762 0.889)
			(layers "B.Cu" "B.Mask" "B.Paste")
			(net "PVDDQ_ABC")
		)
		(pad "2" smd rect
			(at 0 1.397)
			(size 0.762 0.889)
			(layers "B.Cu" "B.Mask" "B.Paste")
			(net "GND")
		)
		(zone
			(layer "B.Cu")
			(hatch none 0.5)
			(connect_pads
				(clearance 0)
			)
			(min_thickness 0.25)
			(keepout
				(tracks not_allowed)
				(vias allowed)
				(pads allowed)
				(copperpour not_allowed)
				(footprints allowed)
			)
			(placement
				(enabled no)
				(sheetname "")
			)
			(fill
				(thermal_gap 0.5)
				(thermal_bridge_width 0.5)
				(island_removal_mode 0)
			)
			(polygon
				(pts
					(xy 184.87009 -0.305308) (xy 185.63209 -0.305308) (xy 185.63209 -0.813308) (xy 184.87009 -0.813308)
				)
			)
		)
	)
)
